# SCM (Grand Teton) — schematic netlist excerpt (pin names and nets, part order shuffled) for the footprints in the layout excerpt that follows; sources: Cadence DE-HDL packaged netlist, KiCad conversion of 12092022_DA0F0TMDCD0_F0T_Management_Board_D_brd_V3_OCP.brd

R155  Q_RES  0 5% CHIP  pkg 0402LF  page 13 : A = P3V3_AUX ; B = P3V3_P2V5_P1V8_RVDD
R768  Q_RES  8.2K 5% CHIP  pkg 0402LF  page 50 : A = P3V3_AUX ; B = REAR_PWR_BTN_N

(kicad_pcb
	(version 20260206)
	(generator "pcbnew")
	(generator_version "10.0")
	(general
		(thickness 1.6)
		(legacy_teardrops no)
	)
	(paper "A4")
	(title_block
		(title "12092022_DA0F0TMDCD0_F0T_Management_Board_D_brd_V3_OCP.brd")
		(comment 1 "Grand Teton / footprints 330-331 of 1440")
	)
	(layers
		(0 "F.Cu" signal "TOP")
		(4 "In1.Cu" signal "GND")
		(6 "In2.Cu" signal "IN1")
		(8 "In3.Cu" signal "GND1")
		(10 "In4.Cu" signal "IN2")
		(12 "In5.Cu" signal "VCC")
		(14 "In6.Cu" signal "VCC1")
		(16 "In7.Cu" signal "IN3")
		(18 "In8.Cu" signal "GND2")
		(20 "In9.Cu" signal "IN4")
		(22 "In10.Cu" signal "GND3")
		(2 "B.Cu" signal "BOTTOM")
		(9 "F.Adhes" user "F.Adhesive")
		(11 "B.Adhes" user "B.Adhesive")
		(13 "F.Paste" user "Package Geometry/Pastemask Top")
		(15 "B.Paste" user "Package Geometry/Pastemask Bottom")
		(5 "F.SilkS" user "Ref Des/Silkscreen Top")
		(7 "B.SilkS" user "Ref Des/Silkscreen Bottom")
		(1 "F.Mask" user "Board Geometry/Soldermask Top")
		(3 "B.Mask" user "Board Geometry/Soldermask Bottom")
		(17 "Dwgs.User" user "User.Drawings")
		(19 "Cmts.User" user "User.Comments")
		(21 "Eco1.User" user "User.Eco1")
		(23 "Eco2.User" user "User.Eco2")
		(25 "Edge.Cuts" user "Board Geometry/Outline")
		(27 "Margin" user)
		(31 "F.CrtYd" user "Package Geometry/Place Bound Top")
		(29 "B.CrtYd" user "Package Geometry/Place Bound Bottom")
		(35 "F.Fab" user "Ref Des/Assembly Top")
		(33 "B.Fab" user "Ref Des/Assembly Bottom")
	)
	(footprint ""
		(layer "F.Cu")
		(at 11.557 -9.652)
		(property "Reference" "R768"
			(at 0 0 0)
			(layer "F.SilkS")
			(hide yes)
			(effects
				(font
					(size 1.27 1.27)
				)
			)
		)
		(property "Value" ""
			(at 0 0 0)
			(layer "F.Fab")
			(effects
				(font
					(size 1.27 1.27)
				)
			)
		)
		(duplicate_pad_numbers_are_jumpers no)
		(fp_line
			(start -0.7874 -0.4064)
			(end 0.7874 -0.4064)
			(stroke
				(width 0.1524)
				(type default)
			)
			(layer "F.SilkS")
		)
		(fp_line
			(start -0.7874 0.4064)
			(end -0.7874 -0.4064)
			(stroke
				(width 0.1524)
				(type default)
			)
			(layer "F.SilkS")
		)
		(fp_line
			(start 0.7874 -0.4064)
			(end 0.7874 0.4064)
			(stroke
				(width 0.1524)
				(type default)
			)
			(layer "F.SilkS")
		)
		(fp_line
			(start 0.7874 0.4064)
			(end -0.7874 0.4064)
			(stroke
				(width 0.1524)
				(type default)
			)
			(layer "F.SilkS")
		)
		(fp_line
			(start -0.67945 -0.305054)
			(end -0.12065 -0.305054)
			(stroke
				(width 0.1)
				(type default)
			)
			(layer "F.Fab")
		)
		(fp_line
			(start -0.67945 0.3048)
			(end -0.67945 -0.305054)
			(stroke
				(width 0.1)
				(type default)
			)
			(layer "F.Fab")
		)
		(fp_line
			(start -0.12065 -0.305054)
			(end -0.12065 -0.2794)
			(stroke
				(width 0.1)
				(type default)
			)
			(layer "F.Fab")
		)
		(fp_line
			(start -0.12065 -0.2794)
			(end 0.12065 -0.2794)
			(stroke
				(width 0.1)
				(type default)
			)
			(layer "F.Fab")
		)
		(fp_line
			(start -0.12065 0.2794)
			(end -0.12065 0.3048)
			(stroke
				(width 0.1)
				(type default)
			)
			(layer "F.Fab")
		)
		(fp_line
			(start -0.12065 0.3048)
			(end -0.67945 0.3048)
			(stroke
				(width 0.1)
				(type default)
			)
			(layer "F.Fab")
		)
		(fp_line
			(start 0.120396 0.2794)
			(end -0.12065 0.2794)
			(stroke
				(width 0.1)
				(type default)
			)
			(layer "F.Fab")
		)
		(fp_line
			(start 0.120396 0.3048)
			(end 0.120396 0.2794)
			(stroke
				(width 0.1)
				(type default)
			)
			(layer "F.Fab")
		)
		(fp_line
			(start 0.12065 -0.3048)
			(end 0.67945 -0.3048)
			(stroke
				(width 0.1)
				(type default)
			)
			(layer "F.Fab")
		)
		(fp_line
			(start 0.12065 -0.2794)
			(end 0.12065 -0.3048)
			(stroke
				(width 0.1)
				(type default)
			)
			(layer "F.Fab")
		)
		(fp_line
			(start 0.67945 -0.3048)
			(end 0.67945 0.3048)
			(stroke
				(width 0.1)
				(type default)
			)
			(layer "F.Fab")
		)
		(fp_line
			(start 0.67945 0.3048)
			(end 0.120396 0.3048)
			(stroke
				(width 0.1)
				(type default)
			)
			(layer "F.Fab")
		)
		(pad "1" smd circle
			(at -0.40005 0)
			(size 0 0)
			(layers "F.Cu" "F.Mask" "F.Paste")
			(net "P3V3_AUX")
		)
		(pad "2" smd circle
			(at 0.40005 0)
			(size 0 0)
			(layers "F.Cu" "F.Mask" "F.Paste")
			(net "REAR_PWR_BTN_N")
		)
	)
	(footprint ""
		(layer "F.Cu")
		(at 37.690298 -38.53561 -90)
		(property "Reference" "R155"
			(at 0 0 270)
			(layer "F.SilkS")
			(hide yes)
			(effects
				(font
					(size 1.27 1.27)
				)
			)
		)
		(property "Value" ""
			(at 0 0 270)
			(layer "F.Fab")
			(effects
				(font
					(size 1.27 1.27)
				)
			)
		)
		(duplicate_pad_numbers_are_jumpers no)
		(fp_line
			(start -0.7874 0.4064)
			(end -0.7874 -0.4064)
			(stroke
				(width 0.1524)
				(type default)
			)
			(layer "F.SilkS")
		)
		(fp_line
			(start 0.7874 0.4064)
			(end -0.7874 0.4064)
			(stroke
				(width 0.1524)
				(type default)
			)
			(layer "F.SilkS")
		)
		(fp_line
			(start -0.7874 -0.4064)
			(end 0.7874 -0.4064)
			(stroke
				(width 0.1524)
				(type default)
			)
			(layer "F.SilkS")
		)
		(fp_line
			(start 0.7874 -0.4064)
			(end 0.7874 0.4064)
			(stroke
				(width 0.1524)
				(type default)
			)
			(layer "F.SilkS")
		)
		(fp_line
			(start -0.67945 0.3048)
			(end -0.67945 -0.305054)
			(stroke
				(width 0.1)
				(type default)
			)
			(layer "F.Fab")
		)
		(fp_line
			(start -0.12065 0.3048)
			(end -0.67945 0.3048)
			(stroke
				(width 0.1)
				(type default)
			)
			(layer "F.Fab")
		)
		(fp_line
			(start 0.120396 0.3048)
			(end 0.120396 0.2794)
			(stroke
				(width 0.1)
				(type default)
			)
			(layer "F.Fab")
		)
		(fp_line
			(start 0.67945 0.3048)
			(end 0.120396 0.3048)
			(stroke
				(width 0.1)
				(type default)
			)
			(layer "F.Fab")
		)
		(fp_line
			(start -0.12065 0.2794)
			(end -0.12065 0.3048)
			(stroke
				(width 0.1)
				(type default)
			)
			(layer "F.Fab")
		)
		(fp_line
			(start 0.120396 0.2794)
			(end -0.12065 0.2794)
			(stroke
				(width 0.1)
				(type default)
			)
			(layer "F.Fab")
		)
		(fp_line
			(start -0.12065 -0.2794)
			(end 0.12065 -0.2794)
			(stroke
				(width 0.1)
				(type default)
			)
			(layer "F.Fab")
		)
		(fp_line
			(start 0.12065 -0.2794)
			(end 0.12065 -0.3048)
			(stroke
				(width 0.1)
				(type default)
			)
			(layer "F.Fab")
		)
		(fp_line
			(start 0.12065 -0.3048)
			(end 0.67945 -0.3048)
			(stroke
				(width 0.1)
				(type default)
			)
			(layer "F.Fab")
		)
		(fp_line
			(start 0.67945 -0.3048)
			(end 0.67945 0.3048)
			(stroke
				(width 0.1)
				(type default)
			)
			(layer "F.Fab")
		)
		(fp_line
			(start -0.67945 -0.305054)
			(end -0.12065 -0.305054)
			(stroke
				(width 0.1)
				(type default)
			)
			(layer "F.Fab")
		)
		(fp_line
			(start -0.12065 -0.305054)
			(end -0.12065 -0.2794)
			(stroke
				(width 0.1)
				(type default)
			)
			(layer "F.Fab")
		)
		(pad "1" smd circle
			(at -0.40005 0 270)
			(size 0 0)
			(layers "F.Cu" "F.Mask" "F.Paste")
			(net "P3V3_AUX")
		)
		(pad "2" smd circle
			(at 0.40005 0 270)
			(size 0 0)
			(layers "F.Cu" "F.Mask" "F.Paste")
			(net "P3V3_P2V5_P1V8_RVDD")
		)
	)
)
